(kicad_pcb
	(version 20260206)
	(generator "pcbnew")
	(generator_version "10.0")
	(general
		(thickness 1.6)
		(legacy_teardrops no)
	)
	(paper "A4")
	(title_block
		(title "03242023_DA0F0TMBIJ0_F0T_Motherboard_J_brd_V01_OCP.brd")
		(comment 1 "Grand Teton / footprints 5723-5728 of 6105")
	)
	(layers
		(0 "F.Cu" signal "TOP")
		(4 "In1.Cu" signal "GND")
		(6 "In2.Cu" signal "IN1")
		(8 "In3.Cu" signal "GND1")
		(10 "In4.Cu" signal "IN2")
		(12 "In5.Cu" signal "GND2")
		(14 "In6.Cu" signal "IN3")
		(16 "In7.Cu" signal "GND3")
		(18 "In8.Cu" signal "VCC")
		(20 "In9.Cu" signal "VCC1")
		(22 "In10.Cu" signal "GND4")
		(24 "In11.Cu" signal "IN4")
		(26 "In12.Cu" signal "GND5")
		(28 "In13.Cu" signal "IN5")
		(30 "In14.Cu" signal "GND6")
		(32 "In15.Cu" signal "IN6")
		(34 "In16.Cu" signal "GND7")
		(2 "B.Cu" signal "BOTTOM")
		(9 "F.Adhes" user "F.Adhesive")
		(11 "B.Adhes" user "B.Adhesive")
		(13 "F.Paste" user "Package Geometry/Pastemask Top")
		(15 "B.Paste" user "Package Geometry/Pastemask Bottom")
		(5 "F.SilkS" user "Ref Des/Silkscreen Top")
		(7 "B.SilkS" user "Ref Des/Silkscreen Bottom")
		(1 "F.Mask" user "Board Geometry/Soldermask Top")
		(3 "B.Mask" user "Board Geometry/Soldermask Bottom")
		(17 "Dwgs.User" user "User.Drawings")
		(19 "Cmts.User" user "User.Comments")
		(21 "Eco1.User" user "User.Eco1")
		(23 "Eco2.User" user "User.Eco2")
		(25 "Edge.Cuts" user "Board Geometry/Outline")
		(27 "Margin" user)
		(31 "F.CrtYd" user "Package Geometry/Place Bound Top")
		(29 "B.CrtYd" user "Package Geometry/Place Bound Bottom")
		(35 "F.Fab" user "Ref Des/Assembly Top")
		(33 "B.Fab" user "Ref Des/Assembly Bottom")
	)
	(footprint ""
		(layer "B.Cu")
		(at 233.5149 -249.182128 -90)
		(property "Reference" "R4077"
			(at 0 0 90)
			(layer "B.SilkS")
			(hide yes)
			(effects
				(font
					(size 1.27 1.27)
				)
				(justify mirror)
			)
		)
		(property "Value" ""
			(at 0 0 90)
			(layer "B.Fab")
			(effects
				(font
					(size 1.27 1.27)
				)
				(justify mirror)
			)
		)
		(duplicate_pad_numbers_are_jumpers no)
		(fp_line
			(start -0.7874 0.4064)
			(end 0.7874 0.4064)
			(stroke
				(width 0.1524)
				(type default)
			)
			(layer "B.SilkS")
		)
		(fp_line
			(start 0.7874 0.4064)
			(end 0.7874 -0.4064)
			(stroke
				(width 0.1524)
				(type default)
			)
			(layer "B.SilkS")
		)
		(fp_line
			(start -0.7874 -0.4064)
			(end -0.7874 0.4064)
			(stroke
				(width 0.1524)
				(type default)
			)
			(layer "B.SilkS")
		)
		(fp_line
			(start 0.7874 -0.4064)
			(end -0.7874 -0.4064)
			(stroke
				(width 0.1524)
				(type default)
			)
			(layer "B.SilkS")
		)
		(fp_line
			(start -0.67945 0.3048)
			(end -0.120396 0.3048)
			(stroke
				(width 0.1)
				(type default)
			)
			(layer "B.Fab")
		)
		(fp_line
			(start -0.120396 0.3048)
			(end -0.120396 0.2794)
			(stroke
				(width 0.1)
				(type default)
			)
			(layer "B.Fab")
		)
		(fp_line
			(start 0.12065 0.3048)
			(end 0.67945 0.3048)
			(stroke
				(width 0.1)
				(type default)
			)
			(layer "B.Fab")
		)
		(fp_line
			(start 0.67945 0.3048)
			(end 0.67945 -0.305054)
			(stroke
				(width 0.1)
				(type default)
			)
			(layer "B.Fab")
		)
		(fp_line
			(start -0.120396 0.2794)
			(end 0.12065 0.2794)
			(stroke
				(width 0.1)
				(type default)
			)
			(layer "B.Fab")
		)
		(fp_line
			(start 0.12065 0.2794)
			(end 0.12065 0.3048)
			(stroke
				(width 0.1)
				(type default)
			)
			(layer "B.Fab")
		)
		(fp_line
			(start -0.12065 -0.2794)
			(end -0.12065 -0.3048)
			(stroke
				(width 0.1)
				(type default)
			)
			(layer "B.Fab")
		)
		(fp_line
			(start 0.12065 -0.2794)
			(end -0.12065 -0.2794)
			(stroke
				(width 0.1)
				(type default)
			)
			(layer "B.Fab")
		)
		(fp_line
			(start -0.67945 -0.3048)
			(end -0.67945 0.3048)
			(stroke
				(width 0.1)
				(type default)
			)
			(layer "B.Fab")
		)
		(fp_line
			(start -0.12065 -0.3048)
			(end -0.67945 -0.3048)
			(stroke
				(width 0.1)
				(type default)
			)
			(layer "B.Fab")
		)
		(fp_line
			(start 0.12065 -0.305054)
			(end 0.12065 -0.2794)
			(stroke
				(width 0.1)
				(type default)
			)
			(layer "B.Fab")
		)
		(fp_line
			(start 0.67945 -0.305054)
			(end 0.12065 -0.305054)
			(stroke
				(width 0.1)
				(type default)
			)
			(layer "B.Fab")
		)
		(pad "1" smd circle
			(at 0.40005 0 90)
			(size 0 0)
			(layers "B.Cu" "B.Mask" "B.Paste")
			(net "VFG3P3_CLK_GEN")
		)
		(pad "2" smd circle
			(at -0.40005 0 90)
			(size 0 0)
			(layers "B.Cu" "B.Mask" "B.Paste")
			(net "VFG_3P3A_CLK_GEN")
		)
	)
	(footprint ""
		(layer "B.Cu")
		(at 138.77798 -30.157928 -90)
		(property "Reference" "C2323"
			(at 0 0 90)
			(layer "B.SilkS")
			(hide yes)
			(effects
				(font
					(size 1.27 1.27)
				)
				(justify mirror)
			)
		)
		(property "Value" ""
			(at 0 0 90)
			(layer "B.Fab")
			(effects
				(font
					(size 1.27 1.27)
				)
				(justify mirror)
			)
		)
		(duplicate_pad_numbers_are_jumpers no)
		(fp_line
			(start -0.7874 0.4064)
			(end 0.7874 0.4064)
			(stroke
				(width 0.1524)
				(type default)
			)
			(layer "B.SilkS")
		)
		(fp_line
			(start 0.7874 0.4064)
			(end 0.7874 -0.4064)
			(stroke
				(width 0.1524)
				(type default)
			)
			(layer "B.SilkS")
		)
		(fp_line
			(start -0.7874 -0.4064)
			(end -0.7874 0.4064)
			(stroke
				(width 0.1524)
				(type default)
			)
			(layer "B.SilkS")
		)
		(fp_line
			(start 0.7874 -0.4064)
			(end -0.7874 -0.4064)
			(stroke
				(width 0.1524)
				(type default)
			)
			(layer "B.SilkS")
		)
		(fp_line
			(start -0.67945 0.3048)
			(end -0.120396 0.3048)
			(stroke
				(width 0.1)
				(type default)
			)
			(layer "B.Fab")
		)
		(fp_line
			(start -0.120396 0.3048)
			(end -0.120396 0.2794)
			(stroke
				(width 0.1)
				(type default)
			)
			(layer "B.Fab")
		)
		(fp_line
			(start 0.12065 0.3048)
			(end 0.67945 0.3048)
			(stroke
				(width 0.1)
				(type default)
			)
			(layer "B.Fab")
		)
		(fp_line
			(start 0.67945 0.3048)
			(end 0.67945 -0.305054)
			(stroke
				(width 0.1)
				(type default)
			)
			(layer "B.Fab")
		)
		(fp_line
			(start -0.120396 0.2794)
			(end 0.12065 0.2794)
			(stroke
				(width 0.1)
				(type default)
			)
			(layer "B.Fab")
		)
		(fp_line
			(start 0.12065 0.2794)
			(end 0.12065 0.3048)
			(stroke
				(width 0.1)
				(type default)
			)
			(layer "B.Fab")
		)
		(fp_line
			(start -0.12065 -0.2794)
			(end -0.12065 -0.3048)
			(stroke
				(width 0.1)
				(type default)
			)
			(layer "B.Fab")
		)
		(fp_line
			(start 0.12065 -0.2794)
			(end -0.12065 -0.2794)
			(stroke
				(width 0.1)
				(type default)
			)
			(layer "B.Fab")
		)
		(fp_line
			(start -0.67945 -0.3048)
			(end -0.67945 0.3048)
			(stroke
				(width 0.1)
				(type default)
			)
			(layer "B.Fab")
		)
		(fp_line
			(start -0.12065 -0.3048)
			(end -0.67945 -0.3048)
			(stroke
				(width 0.1)
				(type default)
			)
			(layer "B.Fab")
		)
		(fp_line
			(start 0.12065 -0.305054)
			(end 0.12065 -0.2794)
			(stroke
				(width 0.1)
				(type default)
			)
			(layer "B.Fab")
		)
		(fp_line
			(start 0.67945 -0.305054)
			(end 0.12065 -0.305054)
			(stroke
				(width 0.1)
				(type default)
			)
			(layer "B.Fab")
		)
		(pad "1" smd circle
			(at 0.40005 0 90)
			(size 0 0)
			(layers "B.Cu" "B.Mask" "B.Paste")
			(net "P3V3_AUX")
		)
		(pad "2" smd circle
			(at -0.40005 0 90)
			(size 0 0)
			(layers "B.Cu" "B.Mask" "B.Paste")
			(net "GND")
		)
	)
	(footprint ""
		(layer "B.Cu")
		(at 89.394284 -184.015888 90)
		(property "Reference" "R999"
			(at 0 0 90)
			(layer "B.SilkS")
			(hide yes)
			(effects
				(font
					(size 1.27 1.27)
				)
				(justify mirror)
			)
		)
		(property "Value" ""
			(at 0 0 90)
			(layer "B.Fab")
			(effects
				(font
					(size 1.27 1.27)
				)
				(justify mirror)
			)
		)
		(duplicate_pad_numbers_are_jumpers no)
		(fp_line
			(start 0.7874 -0.4064)
			(end -0.7874 -0.4064)
			(stroke
				(width 0.1524)
				(type default)
			)
			(layer "B.SilkS")
		)
		(fp_line
			(start -0.7874 -0.4064)
			(end -0.7874 0.4064)
			(stroke
				(width 0.1524)
				(type default)
			)
			(layer "B.SilkS")
		)
		(fp_line
			(start 0.7874 0.4064)
			(end 0.7874 -0.4064)
			(stroke
				(width 0.1524)
				(type default)
			)
			(layer "B.SilkS")
		)
		(fp_line
			(start -0.7874 0.4064)
			(end 0.7874 0.4064)
			(stroke
				(width 0.1524)
				(type default)
			)
			(layer "B.SilkS")
		)
		(fp_line
			(start 0.67945 -0.305054)
			(end 0.12065 -0.305054)
			(stroke
				(width 0.1)
				(type default)
			)
			(layer "B.Fab")
		)
		(fp_line
			(start 0.12065 -0.305054)
			(end 0.12065 -0.2794)
			(stroke
				(width 0.1)
				(type default)
			)
			(layer "B.Fab")
		)
		(fp_line
			(start -0.12065 -0.3048)
			(end -0.67945 -0.3048)
			(stroke
				(width 0.1)
				(type default)
			)
			(layer "B.Fab")
		)
		(fp_line
			(start -0.67945 -0.3048)
			(end -0.67945 0.3048)
			(stroke
				(width 0.1)
				(type default)
			)
			(layer "B.Fab")
		)
		(fp_line
			(start 0.12065 -0.2794)
			(end -0.12065 -0.2794)
			(stroke
				(width 0.1)
				(type default)
			)
			(layer "B.Fab")
		)
		(fp_line
			(start -0.12065 -0.2794)
			(end -0.12065 -0.3048)
			(stroke
				(width 0.1)
				(type default)
			)
			(layer "B.Fab")
		)
		(fp_line
			(start 0.12065 0.2794)
			(end 0.12065 0.3048)
			(stroke
				(width 0.1)
				(type default)
			)
			(layer "B.Fab")
		)
		(fp_line
			(start -0.120396 0.2794)
			(end 0.12065 0.2794)
			(stroke
				(width 0.1)
				(type default)
			)
			(layer "B.Fab")
		)
		(fp_line
			(start 0.67945 0.3048)
			(end 0.67945 -0.305054)
			(stroke
				(width 0.1)
				(type default)
			)
			(layer "B.Fab")
		)
		(fp_line
			(start 0.12065 0.3048)
			(end 0.67945 0.3048)
			(stroke
				(width 0.1)
				(type default)
			)
			(layer "B.Fab")
		)
		(fp_line
			(start -0.120396 0.3048)
			(end -0.120396 0.2794)
			(stroke
				(width 0.1)
				(type default)
			)
			(layer "B.Fab")
		)
		(fp_line
			(start -0.67945 0.3048)
			(end -0.120396 0.3048)
			(stroke
				(width 0.1)
				(type default)
			)
			(layer "B.Fab")
		)
		(pad "1" smd circle
			(at 0.40005 0 270)
			(size 0 0)
			(layers "B.Cu" "B.Mask" "B.Paste")
			(net "FM_SMB_PEHPCPU1_PCIE_ALERT_N")
		)
		(pad "2" smd circle
			(at -0.40005 0 270)
			(size 0 0)
			(layers "B.Cu" "B.Mask" "B.Paste")
			(net "FM_SMB_PEHPCPU1_PCIE_ALERT_R_N")
		)
	)
	(footprint ""
		(layer "B.Cu")
		(at 27.0383 -130.396996)
		(property "Reference" "PR259"
			(at 0 0 0)
			(layer "B.SilkS")
			(hide yes)
			(effects
				(font
					(size 1.27 1.27)
				)
				(justify mirror)
			)
		)
		(property "Value" ""
			(at 0 0 0)
			(layer "B.Fab")
			(effects
				(font
					(size 1.27 1.27)
				)
				(justify mirror)
			)
		)
		(duplicate_pad_numbers_are_jumpers no)
		(fp_line
			(start -0.7874 -0.4064)
			(end -0.7874 0.4064)
			(stroke
				(width 0.1524)
				(type default)
			)
			(layer "B.SilkS")
		)
		(fp_line
			(start -0.7874 0.4064)
			(end 0.7874 0.4064)
			(stroke
				(width 0.1524)
				(type default)
			)
			(layer "B.SilkS")
		)
		(fp_line
			(start 0.7874 -0.4064)
			(end -0.7874 -0.4064)
			(stroke
				(width 0.1524)
				(type default)
			)
			(layer "B.SilkS")
		)
		(fp_line
			(start 0.7874 0.4064)
			(end 0.7874 -0.4064)
			(stroke
				(width 0.1524)
				(type default)
			)
			(layer "B.SilkS")
		)
		(fp_line
			(start -0.67945 -0.3048)
			(end -0.67945 0.3048)
			(stroke
				(width 0.1)
				(type default)
			)
			(layer "B.Fab")
		)
		(fp_line
			(start -0.67945 0.3048)
			(end -0.120396 0.3048)
			(stroke
				(width 0.1)
				(type default)
			)
			(layer "B.Fab")
		)
		(fp_line
			(start -0.12065 -0.3048)
			(end -0.67945 -0.3048)
			(stroke
				(width 0.1)
				(type default)
			)
			(layer "B.Fab")
		)
		(fp_line
			(start -0.12065 -0.2794)
			(end -0.12065 -0.3048)
			(stroke
				(width 0.1)
				(type default)
			)
			(layer "B.Fab")
		)
		(fp_line
			(start -0.120396 0.2794)
			(end 0.12065 0.2794)
			(stroke
				(width 0.1)
				(type default)
			)
			(layer "B.Fab")
		)
		(fp_line
			(start -0.120396 0.3048)
			(end -0.120396 0.2794)
			(stroke
				(width 0.1)
				(type default)
			)
			(layer "B.Fab")
		)
		(fp_line
			(start 0.12065 -0.305054)
			(end 0.12065 -0.2794)
			(stroke
				(width 0.1)
				(type default)
			)
			(layer "B.Fab")
		)
		(fp_line
			(start 0.12065 -0.2794)
			(end -0.12065 -0.2794)
			(stroke
				(width 0.1)
				(type default)
			)
			(layer "B.Fab")
		)
		(fp_line
			(start 0.12065 0.2794)
			(end 0.12065 0.3048)
			(stroke
				(width 0.1)
				(type default)
			)
			(layer "B.Fab")
		)
		(fp_line
			(start 0.12065 0.3048)
			(end 0.67945 0.3048)
			(stroke
				(width 0.1)
				(type default)
			)
			(layer "B.Fab")
		)
		(fp_line
			(start 0.67945 -0.305054)
			(end 0.12065 -0.305054)
			(stroke
				(width 0.1)
				(type default)
			)
			(layer "B.Fab")
		)
		(fp_line
			(start 0.67945 0.3048)
			(end 0.67945 -0.305054)
			(stroke
				(width 0.1)
				(type default)
			)
			(layer "B.Fab")
		)
		(pad "1" smd circle
			(at 0.40005 0 180)
			(size 0 0)
			(layers "B.Cu" "B.Mask" "B.Paste")
			(net "PVCCINFAON_CPU1_ADDR")
		)
		(pad "2" smd circle
			(at -0.40005 0 180)
			(size 0 0)
			(layers "B.Cu" "B.Mask" "B.Paste")
			(net "GND")
		)
	)
	(footprint ""
		(layer "B.Cu")
		(at 284.075378 -319.392046)
		(property "Reference" "R941"
			(at 0 0 0)
			(layer "B.SilkS")
			(hide yes)
			(effects
				(font
					(size 1.27 1.27)
				)
				(justify mirror)
			)
		)
		(property "Value" ""
			(at 0 0 0)
			(layer "B.Fab")
			(effects
				(font
					(size 1.27 1.27)
				)
				(justify mirror)
			)
		)
		(duplicate_pad_numbers_are_jumpers no)
		(fp_line
			(start -0.7874 -0.4064)
			(end -0.7874 0.4064)
			(stroke
				(width 0.1524)
				(type default)
			)
			(layer "B.SilkS")
		)
		(fp_line
			(start -0.7874 0.4064)
			(end 0.7874 0.4064)
			(stroke
				(width 0.1524)
				(type default)
			)
			(layer "B.SilkS")
		)
		(fp_line
			(start 0.7874 -0.4064)
			(end -0.7874 -0.4064)
			(stroke
				(width 0.1524)
				(type default)
			)
			(layer "B.SilkS")
		)
		(fp_line
			(start 0.7874 0.4064)
			(end 0.7874 -0.4064)
			(stroke
				(width 0.1524)
				(type default)
			)
			(layer "B.SilkS")
		)
		(fp_line
			(start -0.67945 -0.3048)
			(end -0.67945 0.3048)
			(stroke
				(width 0.1)
				(type default)
			)
			(layer "B.Fab")
		)
		(fp_line
			(start -0.67945 0.3048)
			(end -0.120396 0.3048)
			(stroke
				(width 0.1)
				(type default)
			)
			(layer "B.Fab")
		)
		(fp_line
			(start -0.12065 -0.3048)
			(end -0.67945 -0.3048)
			(stroke
				(width 0.1)
				(type default)
			)
			(layer "B.Fab")
		)
		(fp_line
			(start -0.12065 -0.2794)
			(end -0.12065 -0.3048)
			(stroke
				(width 0.1)
				(type default)
			)
			(layer "B.Fab")
		)
		(fp_line
			(start -0.120396 0.2794)
			(end 0.12065 0.2794)
			(stroke
				(width 0.1)
				(type default)
			)
			(layer "B.Fab")
		)
		(fp_line
			(start -0.120396 0.3048)
			(end -0.120396 0.2794)
			(stroke
				(width 0.1)
				(type default)
			)
			(layer "B.Fab")
		)
		(fp_line
			(start 0.12065 -0.305054)
			(end 0.12065 -0.2794)
			(stroke
				(width 0.1)
				(type default)
			)
			(layer "B.Fab")
		)
		(fp_line
			(start 0.12065 -0.2794)
			(end -0.12065 -0.2794)
			(stroke
				(width 0.1)
				(type default)
			)
			(layer "B.Fab")
		)
		(fp_line
			(start 0.12065 0.2794)
			(end 0.12065 0.3048)
			(stroke
				(width 0.1)
				(type default)
			)
			(layer "B.Fab")
		)
		(fp_line
			(start 0.12065 0.3048)
			(end 0.67945 0.3048)
			(stroke
				(width 0.1)
				(type default)
			)
			(layer "B.Fab")
		)
		(fp_line
			(start 0.67945 -0.305054)
			(end 0.12065 -0.305054)
			(stroke
				(width 0.1)
				(type default)
			)
			(layer "B.Fab")
		)
		(fp_line
			(start 0.67945 0.3048)
			(end 0.67945 -0.305054)
			(stroke
				(width 0.1)
				(type default)
			)
			(layer "B.Fab")
		)
		(pad "1" smd circle
			(at 0.40005 0 180)
			(size 0 0)
			(layers "B.Cu" "B.Mask" "B.Paste")
			(net "P3V3_AUX")
		)
		(pad "2" smd circle
			(at -0.40005 0 180)
			(size 0 0)
			(layers "B.Cu" "B.Mask" "B.Paste")
			(net "PWRGD_FAIL_CPU0_CD_R1")
		)
	)
	(footprint ""
		(layer "B.Cu")
		(at 237.488476 -121.236994 180)
		(property "Reference" "C208"
			(at 0 0 0)
			(layer "B.SilkS")
			(hide yes)
			(effects
				(font
					(size 1.27 1.27)
				)
				(justify mirror)
			)
		)
		(property "Value" ""
			(at 0 0 0)
			(layer "B.Fab")
			(effects
				(font
					(size 1.27 1.27)
				)
				(justify mirror)
			)
		)
		(duplicate_pad_numbers_are_jumpers no)
		(fp_line
			(start 1.2954 0.5842)
			(end 1.2954 -0.5842)
			(stroke
				(width 0.1524)
				(type default)
			)
			(layer "B.SilkS")
		)
		(fp_line
			(start 1.2954 -0.5842)
			(end -1.2954 -0.5842)
			(stroke
				(width 0.1524)
				(type default)
			)
			(layer "B.SilkS")
		)
		(fp_line
			(start 0 -0.5842)
			(end 0 0.5842)
			(stroke
				(width 0.1524)
				(type default)
			)
			(layer "B.SilkS")
		)
		(fp_line
			(start -1.2954 0.5842)
			(end 1.2954 0.5842)
			(stroke
				(width 0.1524)
				(type default)
			)
			(layer "B.SilkS")
		)
		(fp_line
			(start -1.2954 -0.5842)
			(end -1.2954 0.5842)
			(stroke
				(width 0.1524)
				(type default)
			)
			(layer "B.SilkS")
		)
		(fp_line
			(start 1.1938 0.4064)
			(end 1.1938 -0.4064)
			(stroke
				(width 0.1)
				(type default)
			)
			(layer "B.Fab")
		)
		(fp_line
			(start 1.1938 -0.4064)
			(end 0.8636 -0.4064)
			(stroke
				(width 0.1)
				(type default)
			)
			(layer "B.Fab")
		)
		(fp_line
			(start 0.8636 0.4572)
			(end 0.8636 0.4064)
			(stroke
				(width 0.1)
				(type default)
			)
			(layer "B.Fab")
		)
		(fp_line
			(start 0.8636 0.4064)
			(end 1.1938 0.4064)
			(stroke
				(width 0.1)
				(type default)
			)
			(layer "B.Fab")
		)
		(fp_line
			(start 0.8636 -0.4064)
			(end 0.8636 -0.4572)
			(stroke
				(width 0.1)
				(type default)
			)
			(layer "B.Fab")
		)
		(fp_line
			(start 0.8636 -0.4572)
			(end -0.8636 -0.4572)
			(stroke
				(width 0.1)
				(type default)
			)
			(layer "B.Fab")
		)
		(fp_line
			(start -0.8636 0.4572)
			(end 0.8636 0.4572)
			(stroke
				(width 0.1)
				(type default)
			)
			(layer "B.Fab")
		)
		(fp_line
			(start -0.8636 0.4064)
			(end -0.8636 0.4572)
			(stroke
				(width 0.1)
				(type default)
			)
			(layer "B.Fab")
		)
		(fp_line
			(start -0.8636 -0.4064)
			(end -1.1938 -0.4064)
			(stroke
				(width 0.1)
				(type default)
			)
			(layer "B.Fab")
		)
		(fp_line
			(start -0.8636 -0.4572)
			(end -0.8636 -0.4064)
			(stroke
				(width 0.1)
				(type default)
			)
			(layer "B.Fab")
		)
		(fp_line
			(start -1.1938 0.4064)
			(end -0.8636 0.4064)
			(stroke
				(width 0.1)
				(type default)
			)
			(layer "B.Fab")
		)
		(fp_line
			(start -1.1938 -0.4064)
			(end -1.1938 0.4064)
			(stroke
				(width 0.1)
				(type default)
			)
			(layer "B.Fab")
		)
		(pad "1" smd rect
			(at 0.7366 0 90)
			(size 0.7112 0.8128)
			(layers "B.Cu" "B.Mask" "B.Paste")
			(net "P3V3_DB2000_VDDR")
		)
		(pad "2" smd rect
			(at -0.7366 0 90)
			(size 0.7112 0.8128)
			(layers "B.Cu" "B.Mask" "B.Paste")
			(net "GND")
		)
	)
)
